%FSTAX23Y23*%
%MOIN*%
%SFA1B1*%

%IPPOS*%
%ADD14C,0.010000*%
%ADD17C,0.006000*%
%ADD187R,1.389760X0.216540*%
%LNtimingcard_pcb-1*%
%LPD*%
G36*
X07007Y0059D02*
X06732D01*
Y00807*
X07007*
Y0059*
G37*
%LNtimingcard_pcb-2*%
%LPC*%
G36*
X06864Y00738D02*
X06851D01*
X068Y00662*
Y00738*
X06788*
Y00642*
X06801*
X06852Y00717*
Y00642*
X06864*
Y00738*
G37*
G36*
X0692Y00739D02*
X06918D01*
X06917Y00739*
X06916Y00739*
X06915Y00739*
X06914Y00739*
X06911Y00739*
X06908Y00738*
X06904Y00737*
X06901Y00736*
X06901*
X06901Y00736*
X069Y00736*
X069Y00735*
X06899Y00735*
X06898Y00734*
X06897Y00733*
X06895Y00732*
X06892Y0073*
X0689Y00728*
X06889Y00726*
X06889Y00726*
X06888Y00725*
X06888Y00725*
X06888Y00725*
X06888Y00724*
X06887Y00723*
X06887Y00722*
X06886Y00721*
X06886Y00719*
X06885Y00717*
X06884Y00714*
X06884Y00711*
X06896Y0071*
Y0071*
X06896Y0071*
Y00711*
X06896Y00711*
X06896Y00712*
X06897Y00713*
X06897Y00715*
X06898Y00717*
X06899Y00719*
X06901Y00721*
X06902Y00722*
X06903Y00723*
X06903Y00723*
X06903Y00724*
X06903Y00724*
X06904Y00724*
X06904Y00724*
X06905Y00725*
X06906Y00725*
X06907Y00726*
X06908Y00726*
X06909Y00727*
X06911Y00727*
X06912Y00727*
X06914Y00728*
X06916Y00728*
X06918Y00728*
X06921*
X06921Y00728*
X06922*
X06923Y00728*
X06925Y00728*
X06926Y00727*
X06929Y00727*
X06931Y00726*
X06934Y00725*
X06935Y00724*
X06936Y00724*
X06936*
X06936Y00724*
X06937Y00723*
X06938Y00722*
X06939Y00721*
X0694Y00719*
X06941Y00718*
X06941Y00716*
X06941Y00715*
X06941Y00714*
Y00713*
Y00713*
X06941Y00713*
X06941Y00712*
X06941Y00711*
X06941Y00709*
X0694Y00708*
X06939Y00706*
X06938Y00705*
X06938Y00705*
X06937Y00705*
X06937Y00704*
X06936Y00704*
X06936Y00704*
X06935Y00703*
X06934Y00703*
X06933Y00702*
X06932Y00702*
X0693Y00701*
X06928Y00701*
X06926Y007*
X06924Y00699*
X06921Y00699*
X06919Y00698*
X06918*
X06918Y00698*
X06917Y00698*
X06916Y00698*
X06915Y00697*
X06913Y00697*
X06912Y00697*
X0691Y00696*
X06907Y00695*
X06903Y00694*
X06901Y00694*
X069Y00693*
X06899Y00693*
X06897Y00692*
X06897*
X06897Y00692*
X06897Y00692*
X06896Y00691*
X06895Y00691*
X06895Y00691*
X06893Y00689*
X06891Y00688*
X06889Y00686*
X06887Y00684*
X06886Y00683*
X06885Y00682*
Y00682*
X06885Y00682*
X06885Y00682*
X06884Y00681*
X06884Y00681*
X06884Y0068*
X06883Y00678*
X06882Y00676*
X06882Y00674*
X06881Y00671*
X06881Y00669*
Y00668*
X06881Y00667*
Y00667*
X06881Y00666*
X06881Y00664*
X06882Y00662*
X06883Y00659*
X06884Y00657*
X06885Y00656*
X06885Y00654*
Y00654*
X06886Y00654*
X06886Y00654*
X06886Y00653*
X06887Y00652*
X06889Y0065*
X0689Y00649*
X06893Y00647*
X06895Y00645*
X06898Y00644*
X06898*
X06898Y00644*
X06899Y00643*
X06899Y00643*
X069Y00643*
X06901Y00643*
X06902Y00642*
X06903Y00642*
X06905Y00642*
X06906Y00641*
X06909Y00641*
X06913Y0064*
X06916Y0064*
X06918*
X06919Y0064*
X0692*
X06921Y0064*
X06923Y0064*
X06924Y00641*
X06928Y00641*
X06931Y00642*
X06935Y00643*
X06938Y00644*
X06939*
X06939Y00644*
X06939Y00644*
X0694Y00645*
X06941Y00645*
X06941Y00645*
X06943Y00647*
X06946Y00648*
X06948Y0065*
X0695Y00652*
X06952Y00655*
X06952Y00655*
X06952Y00655*
X06953Y00656*
X06953Y00657*
X06953Y00657*
X06954Y00658*
X06954Y00659*
X06955Y0066*
X06955Y00661*
X06956Y00663*
X06956Y00666*
X06957Y00669*
X06957Y00671*
X06957Y00673*
X06945Y00674*
Y00673*
Y00673*
X06945Y00673*
X06945Y00672*
X06945Y00672*
X06945Y00671*
X06945Y00669*
X06944Y00667*
X06943Y00665*
X06943Y00663*
X06942Y00662*
X06941Y00661*
X06941Y00661*
X0694Y0066*
X06939Y00659*
X06938Y00658*
X06936Y00657*
X06934Y00655*
X06932Y00654*
X06932*
X06932Y00654*
X06931Y00654*
X06931Y00654*
X0693Y00654*
X06929Y00653*
X06929Y00653*
X06928Y00653*
X06925Y00652*
X06923Y00652*
X0692Y00652*
X06917Y00651*
X06916*
X06915Y00652*
X06914*
X06913Y00652*
X06911Y00652*
X06909Y00652*
X06906Y00653*
X06904Y00653*
X06904*
X06904Y00654*
X06904Y00654*
X06903Y00654*
X06903Y00654*
X06901Y00655*
X069Y00656*
X06898Y00657*
X06897Y00658*
X06896Y00659*
X06896Y0066*
X06896Y0066*
X06895Y00661*
X06895Y00662*
X06894Y00663*
X06894Y00665*
X06893Y00666*
X06893Y00668*
Y00668*
Y00668*
Y00668*
X06893Y00669*
X06894Y0067*
X06894Y00672*
X06894Y00673*
X06895Y00674*
X06896Y00676*
X06896Y00676*
X06896Y00676*
X06897Y00677*
X06898Y00678*
X06899Y00678*
X06901Y00679*
X06903Y0068*
X06905Y00681*
X06905Y00681*
X06905Y00681*
X06905Y00681*
X06906Y00682*
X06906Y00682*
X06907Y00682*
X06908Y00682*
X06909Y00683*
X0691Y00683*
X06912Y00683*
X06913Y00684*
X06915Y00684*
X06917Y00685*
X06919Y00685*
X06922Y00686*
X06922*
X06922Y00686*
X06923Y00686*
X06924Y00686*
X06925Y00687*
X06926Y00687*
X06927Y00687*
X06929Y00688*
X06932Y00689*
X06935Y0069*
X06936Y0069*
X06938Y00691*
X06939Y00691*
X0694Y00692*
X0694*
X0694Y00692*
X06941Y00692*
X06941Y00693*
X06942Y00693*
X06944Y00694*
X06946Y00696*
X06947Y00697*
X06949Y00699*
X0695Y00701*
Y00701*
X06951Y00701*
X06951Y00701*
X06951Y00702*
X06951Y00703*
X06952Y00704*
X06953Y00706*
X06953Y00708*
X06954Y0071*
X06954Y00713*
Y00713*
Y00713*
Y00714*
X06954Y00714*
Y00715*
X06954Y00715*
X06953Y00717*
X06953Y00719*
X06952Y00722*
X06951Y00724*
X0695Y00726*
Y00726*
X06949Y00727*
X06949Y00727*
X06949Y00727*
X06948Y00729*
X06947Y0073*
X06945Y00732*
X06943Y00733*
X0694Y00735*
X06938Y00736*
X06937*
X06937Y00736*
X06937Y00736*
X06936Y00737*
X06936Y00737*
X06935Y00737*
X06934Y00737*
X06932Y00738*
X06931Y00738*
X0693Y00738*
X06927Y00739*
X06924Y00739*
X0692Y00739*
G37*
%LNtimingcard_pcb-3*%
%LPD*%
G54D14*
X0021Y0283D02*
D01*
X0021Y02834*
X00209Y02838*
X00209Y02842*
X00208Y02846*
X00206Y0285*
X00205Y02854*
X00203Y02858*
X00201Y02862*
X00198Y02865*
X00196Y02869*
X00193Y02872*
X0019Y02875*
X00187Y02878*
X00183Y0288*
X0018Y02882*
X00176Y02884*
X00172Y02886*
X00168Y02888*
X00164Y02889*
X0016Y0289*
X00155Y0289*
X00151Y02891*
X00147*
X00143Y0289*
X00138Y0289*
X00134Y02889*
X0013Y02888*
X00126Y02886*
X00122Y02884*
X00118Y02882*
X00115Y0288*
X00111Y02878*
X00108Y02875*
X00105Y02872*
X00102Y02869*
X001Y02865*
X00097Y02862*
X00095Y02858*
X00093Y02854*
X00092Y0285*
X0009Y02846*
X00089Y02842*
X00089Y02838*
X00088Y02834*
X00088Y0283*
X00088Y02825*
X00089Y02821*
X00089Y02817*
X0009Y02813*
X00092Y02809*
X00093Y02805*
X00095Y02801*
X00097Y02797*
X001Y02794*
X00102Y0279*
X00105Y02787*
X00108Y02784*
X00111Y02781*
X00115Y02779*
X00119Y02777*
X00122Y02775*
X00126Y02773*
X0013Y02772*
X00134Y0277*
X00138Y02769*
X00143Y02769*
X00147Y02769*
X00151*
X00155Y02769*
X0016Y02769*
X00164Y0277*
X00168Y02772*
X00172Y02773*
X00176Y02775*
X0018Y02777*
X00183Y02779*
X00187Y02781*
X0019Y02784*
X00193Y02787*
X00196Y0279*
X00198Y02794*
X00201Y02797*
X00203Y02801*
X00205Y02805*
X00206Y02809*
X00208Y02813*
X00209Y02817*
X00209Y02821*
X0021Y02825*
X0021Y0283*
X02592D02*
D01*
X02592Y02834*
X02591Y02838*
X02591Y02842*
X0259Y02846*
X02588Y0285*
X02587Y02854*
X02585Y02858*
X02583Y02862*
X0258Y02865*
X02578Y02869*
X02575Y02872*
X02572Y02875*
X02568Y02878*
X02565Y0288*
X02561Y02882*
X02558Y02884*
X02554Y02886*
X0255Y02888*
X02546Y02889*
X02541Y0289*
X02537Y0289*
X02533Y02891*
X02529*
X02525Y0289*
X0252Y0289*
X02516Y02889*
X02512Y02888*
X02508Y02886*
X02504Y02884*
X025Y02882*
X02497Y0288*
X02493Y02878*
X0249Y02875*
X02487Y02872*
X02484Y02869*
X02482Y02865*
X02479Y02862*
X02477Y02858*
X02475Y02854*
X02474Y0285*
X02472Y02846*
X02471Y02842*
X0247Y02838*
X0247Y02834*
X0247Y0283*
X0247Y02825*
X0247Y02821*
X02471Y02817*
X02472Y02813*
X02474Y02809*
X02475Y02805*
X02477Y02801*
X02479Y02797*
X02482Y02794*
X02484Y0279*
X02487Y02787*
X0249Y02784*
X02493Y02781*
X02497Y02779*
X025Y02777*
X02504Y02775*
X02508Y02773*
X02512Y02772*
X02516Y0277*
X0252Y02769*
X02525Y02769*
X02529Y02769*
X02533*
X02537Y02769*
X02541Y02769*
X02546Y0277*
X0255Y02772*
X02554Y02773*
X02558Y02775*
X02561Y02777*
X02565Y02779*
X02568Y02781*
X02572Y02784*
X02575Y02787*
X02578Y0279*
X0258Y02794*
X02583Y02797*
X02585Y02801*
X02587Y02805*
X02588Y02809*
X0259Y02813*
X02591Y02817*
X02591Y02821*
X02592Y02825*
X02592Y0283*
Y03853D02*
D01*
X02592Y03857*
X02591Y03862*
X02591Y03866*
X0259Y0387*
X02588Y03874*
X02587Y03878*
X02585Y03882*
X02583Y03886*
X0258Y03889*
X02578Y03892*
X02575Y03896*
X02572Y03899*
X02568Y03901*
X02565Y03904*
X02561Y03906*
X02558Y03908*
X02554Y0391*
X0255Y03911*
X02546Y03912*
X02541Y03913*
X02537Y03914*
X02533Y03914*
X02529*
X02525Y03914*
X0252Y03913*
X02516Y03912*
X02512Y03911*
X02508Y0391*
X02504Y03908*
X025Y03906*
X02497Y03904*
X02493Y03901*
X0249Y03899*
X02487Y03896*
X02484Y03892*
X02482Y03889*
X02479Y03886*
X02477Y03882*
X02475Y03878*
X02474Y03874*
X02472Y0387*
X02471Y03866*
X0247Y03862*
X0247Y03857*
X0247Y03853*
X0247Y03849*
X0247Y03845*
X02471Y0384*
X02472Y03836*
X02474Y03832*
X02475Y03828*
X02477Y03825*
X02479Y03821*
X02482Y03817*
X02484Y03814*
X02487Y03811*
X0249Y03808*
X02493Y03805*
X02497Y03803*
X025Y038*
X02504Y03798*
X02508Y03797*
X02512Y03795*
X02516Y03794*
X0252Y03793*
X02525Y03792*
X02529Y03792*
X02533*
X02537Y03792*
X02541Y03793*
X02546Y03794*
X0255Y03795*
X02554Y03797*
X02558Y03798*
X02561Y038*
X02565Y03803*
X02568Y03805*
X02572Y03808*
X02575Y03811*
X02578Y03814*
X0258Y03817*
X02583Y03821*
X02585Y03825*
X02587Y03828*
X02588Y03832*
X0259Y03836*
X02591Y0384*
X02591Y03845*
X02592Y03849*
X02592Y03853*
X00018Y03966D02*
X02662D01*
X00018Y02716D02*
Y03966D01*
Y02716D02*
X02662D01*
Y03966*
X02657Y04032D02*
Y04007D01*
X02652Y04002*
X02642*
X02637Y04007*
Y04032*
X02627Y04002D02*
X02617D01*
X02622*
Y04032*
X02627Y04027*
X02587Y04002D02*
Y04032D01*
X02602Y04017*
X02582*
X02258Y02948D02*
X02263Y02953D01*
X02273*
X02278Y02948*
Y02928*
X02273Y02923*
X02263*
X02258Y02928*
X02248Y02948D02*
X02243Y02953D01*
X02233*
X02228Y02948*
Y02943*
X02233Y02938*
X02228Y02933*
Y02928*
X02233Y02923*
X02243*
X02248Y02928*
Y02933*
X02243Y02938*
X02248Y02943*
Y02948*
X02243Y02938D02*
X02233D01*
X02218Y02953D02*
X02198D01*
Y02948*
X02218Y02928*
Y02923*
X02259Y02859D02*
X02264Y02864D01*
X02274*
X02279Y02859*
Y02839*
X02274Y02834*
X02264*
X02259Y02839*
X02249Y02859D02*
X02244Y02864D01*
X02234*
X02229Y02859*
Y02854*
X02234Y02849*
X02229Y02844*
Y02839*
X02234Y02834*
X02244*
X02249Y02839*
Y02844*
X02244Y02849*
X02249Y02854*
Y02859*
X02244Y02849D02*
X02234D01*
X02219Y02859D02*
X02214Y02864D01*
X02204*
X02199Y02859*
Y02854*
X02204Y02849*
X02199Y02844*
Y02839*
X02204Y02834*
X02214*
X02219Y02839*
Y02844*
X02214Y02849*
X02219Y02854*
Y02859*
X02214Y02849D02*
X02204D01*
X02629Y031D02*
X02634Y03095D01*
Y03085*
X02629Y0308*
X02609*
X02604Y03085*
Y03095*
X02609Y031*
X02629Y0311D02*
X02634Y03115D01*
Y03125*
X02629Y0313*
X02624*
X02619Y03125*
X02614Y0313*
X02609*
X02604Y03125*
Y03115*
X02609Y0311*
X02614*
X02619Y03115*
X02624Y0311*
X02629*
X02619Y03115D02*
Y03125D01*
X02609Y0314D02*
X02604Y03145D01*
Y03155*
X02609Y0316*
X02629*
X02634Y03155*
Y03145*
X02629Y0314*
X02624*
X02619Y03145*
Y0316*
X02721Y0289D02*
X02726Y02885D01*
Y02875*
X02721Y0287*
X02701*
X02696Y02875*
Y02885*
X02701Y0289*
Y029D02*
X02696Y02905D01*
Y02915*
X02701Y0292*
X02721*
X02726Y02915*
Y02905*
X02721Y029*
X02716*
X02711Y02905*
Y0292*
X02721Y0293D02*
X02726Y02935D01*
Y02945*
X02721Y0295*
X02701*
X02696Y02945*
Y02935*
X02701Y0293*
X02721*
X0305Y00461D02*
X03055Y00456D01*
Y00446*
X0305Y00441*
X0303*
X03025Y00446*
Y00456*
X0303Y00461*
X03055Y00491D02*
Y00471D01*
X0304*
X03045Y00481*
Y00486*
X0304Y00491*
X0303*
X03025Y00486*
Y00476*
X0303Y00471*
X0305Y00501D02*
X03055Y00506D01*
Y00516*
X0305Y00521*
X03045*
X0304Y00516*
Y00511*
Y00516*
X03035Y00521*
X0303*
X03025Y00516*
Y00506*
X0303Y00501*
X02984Y00461D02*
X02989Y00456D01*
Y00446*
X02984Y00441*
X02964*
X02959Y00446*
Y00456*
X02964Y00461*
X02989Y00491D02*
Y00471D01*
X02974*
X02979Y00481*
Y00486*
X02974Y00491*
X02964*
X02959Y00486*
Y00476*
X02964Y00471*
X02959Y00521D02*
Y00501D01*
X02979Y00521*
X02984*
X02989Y00516*
Y00506*
X02984Y00501*
X02889Y00461D02*
X02894Y00456D01*
Y00446*
X02889Y00441*
X02869*
X02864Y00446*
Y00456*
X02869Y00461*
X02894Y00491D02*
Y00471D01*
X02879*
X02884Y00481*
Y00486*
X02879Y00491*
X02869*
X02864Y00486*
Y00476*
X02869Y00471*
X02864Y00501D02*
Y00511D01*
Y00506*
X02894*
X02889Y00501*
X02818Y00461D02*
X02823Y00456D01*
Y00446*
X02818Y00441*
X02798*
X02793Y00446*
Y00456*
X02798Y00461*
X02823Y00491D02*
Y00471D01*
X02808*
X02813Y00481*
Y00486*
X02808Y00491*
X02798*
X02793Y00486*
Y00476*
X02798Y00471*
X02818Y00501D02*
X02823Y00506D01*
Y00516*
X02818Y00521*
X02798*
X02793Y00516*
Y00506*
X02798Y00501*
X02818*
X02727Y00461D02*
X02732Y00456D01*
Y00446*
X02727Y00441*
X02707*
X02702Y00446*
Y00456*
X02707Y00461*
X02702Y00486D02*
X02732D01*
X02717Y00471*
Y00491*
X02707Y00501D02*
X02702Y00506D01*
Y00516*
X02707Y00521*
X02727*
X02732Y00516*
Y00506*
X02727Y00501*
X02722*
X02717Y00506*
Y00521*
X02659Y00461D02*
X02664Y00456D01*
Y00446*
X02659Y00441*
X02639*
X02634Y00446*
Y00456*
X02639Y00461*
X02634Y00486D02*
X02664D01*
X02649Y00471*
Y00491*
X02659Y00501D02*
X02664Y00506D01*
Y00516*
X02659Y00521*
X02654*
X02649Y00516*
X02644Y00521*
X02639*
X02634Y00516*
Y00506*
X02639Y00501*
X02644*
X02649Y00506*
X02654Y00501*
X02659*
X02649Y00506D02*
Y00516D01*
X02544Y00461D02*
X02549Y00456D01*
Y00446*
X02544Y00441*
X02524*
X02519Y00446*
Y00456*
X02524Y00461*
X02519Y00486D02*
X02549D01*
X02534Y00471*
Y00491*
X02549Y00501D02*
Y00521D01*
X02544*
X02524Y00501*
X02519*
X02475Y00461D02*
X0248Y00456D01*
Y00446*
X02475Y00441*
X02455*
X0245Y00446*
Y00456*
X02455Y00461*
X0245Y00486D02*
X0248D01*
X02465Y00471*
Y00491*
X0248Y00521D02*
X02475Y00511D01*
X02465Y00501*
X02455*
X0245Y00506*
Y00516*
X02455Y00521*
X0246*
X02465Y00516*
Y00501*
X024Y00477D02*
X02405Y00472D01*
Y00462*
X024Y00457*
X0238*
X02375Y00462*
Y00472*
X0238Y00477*
X02375Y00502D02*
X02405D01*
X0239Y00487*
Y00507*
X02405Y00537D02*
Y00517D01*
X0239*
X02395Y00527*
Y00532*
X0239Y00537*
X0238*
X02375Y00532*
Y00522*
X0238Y00517*
X02331Y00479D02*
X02336Y00474D01*
Y00464*
X02331Y00459*
X02311*
X02306Y00464*
Y00474*
X02311Y00479*
X02306Y00504D02*
X02336D01*
X02321Y00489*
Y00509*
X02306Y00534D02*
X02336D01*
X02321Y00519*
Y00539*
G54D17*
X0267Y02977D02*
Y03037D01*
X02594Y02977D02*
Y03037D01*
X02332Y02982D02*
X02392D01*
X02332Y02906D02*
X02392D01*
G54D187*
X06049Y00698D03*
M02*